# Thunderbolt to 10GbE adapter — KiCad custom design rules (.kicad_dru)
(version 1)

# 85 Ohm

(rule "85Ohm-diff_outer"
	(layer outer)
	(condition "A.NetClass == '85Ohm*'")
	(constraint track_width (opt 0.19mm))
	(constraint diff_pair_gap (opt 0.16mm))
)

(rule "85Ohm-diff_inner"
	(layer inner)
	(condition "A.NetClass == '85Ohm*'")
	(constraint track_width (opt 0.21mm))
	(constraint diff_pair_gap (opt 0.14mm))
)

# 100 Ohm

(rule "100Ohm-diff_outer"
	(layer outer)
	(condition "A.NetClass == '100Ohm*'")
	(constraint track_width (opt 0.15mm))
	(constraint diff_pair_gap (opt 0.20mm))
)

(rule "100Ohm-diff_inner"
	(layer inner)
	(condition "A.NetClass == '100Ohm*'")
	(constraint track_width (opt 0.14mm))
	(constraint diff_pair_gap (opt 0.21mm))
)

# 90 Ohm

# Calculated as 87 Ohm int, 95 Ohm ext

(rule "90Ohm-diff_outer"
	(layer outer)
	(condition "A.NetClass == '90Ohm*'")
	(constraint track_width (opt 0.16mm))
	(constraint diff_pair_gap (opt 0.14mm))
)

(rule "90Ohm-diff_inner"
	(layer inner)
	(condition "A.NetClass == '90Ohm*'")
	(constraint track_width (opt 0.16mm))
	(constraint diff_pair_gap (opt 0.14mm))
)
